(kicad_pcb
	(version 20260206)
	(generator "pcbnew")
	(generator_version "10.0")
	(general
		(thickness 1.6)
		(legacy_teardrops no)
	)
	(paper "A4")
	(title_block
		(title "03242023_DA0F0TMBIJ0_F0T_Motherboard_J_brd_V01_OCP.brd")
		(comment 1 "Grand Teton / footprints 3110-3117 of 6105")
	)
	(layers
		(0 "F.Cu" signal "TOP")
		(4 "In1.Cu" signal "GND")
		(6 "In2.Cu" signal "IN1")
		(8 "In3.Cu" signal "GND1")
		(10 "In4.Cu" signal "IN2")
		(12 "In5.Cu" signal "GND2")
		(14 "In6.Cu" signal "IN3")
		(16 "In7.Cu" signal "GND3")
		(18 "In8.Cu" signal "VCC")
		(20 "In9.Cu" signal "VCC1")
		(22 "In10.Cu" signal "GND4")
		(24 "In11.Cu" signal "IN4")
		(26 "In12.Cu" signal "GND5")
		(28 "In13.Cu" signal "IN5")
		(30 "In14.Cu" signal "GND6")
		(32 "In15.Cu" signal "IN6")
		(34 "In16.Cu" signal "GND7")
		(2 "B.Cu" signal "BOTTOM")
		(9 "F.Adhes" user "F.Adhesive")
		(11 "B.Adhes" user "B.Adhesive")
		(13 "F.Paste" user "Package Geometry/Pastemask Top")
		(15 "B.Paste" user "Package Geometry/Pastemask Bottom")
		(5 "F.SilkS" user "Ref Des/Silkscreen Top")
		(7 "B.SilkS" user "Ref Des/Silkscreen Bottom")
		(1 "F.Mask" user "Board Geometry/Soldermask Top")
		(3 "B.Mask" user "Board Geometry/Soldermask Bottom")
		(17 "Dwgs.User" user "User.Drawings")
		(19 "Cmts.User" user "User.Comments")
		(21 "Eco1.User" user "User.Eco1")
		(23 "Eco2.User" user "User.Eco2")
		(25 "Edge.Cuts" user "Board Geometry/Outline")
		(27 "Margin" user)
		(31 "F.CrtYd" user "Package Geometry/Place Bound Top")
		(29 "B.CrtYd" user "Package Geometry/Place Bound Bottom")
		(35 "F.Fab" user "Ref Des/Assembly Top")
		(33 "B.Fab" user "Ref Des/Assembly Bottom")
	)
	(footprint ""
		(layer "F.Cu")
		(at 216.065608 -405.839422 180)
		(property "Reference" "PC2226"
			(at 0 0 180)
			(layer "F.SilkS")
			(hide yes)
			(effects
				(font
					(size 1.27 1.27)
				)
			)
		)
		(property "Value" ""
			(at 0 0 180)
			(layer "F.Fab")
			(effects
				(font
					(size 1.27 1.27)
				)
			)
		)
		(duplicate_pad_numbers_are_jumpers no)
		(fp_line
			(start 0.7874 0.4064)
			(end -0.7874 0.4064)
			(stroke
				(width 0.1524)
				(type default)
			)
			(layer "F.SilkS")
		)
		(fp_line
			(start 0.7874 -0.4064)
			(end 0.7874 0.4064)
			(stroke
				(width 0.1524)
				(type default)
			)
			(layer "F.SilkS")
		)
		(fp_line
			(start -0.7874 0.4064)
			(end -0.7874 -0.4064)
			(stroke
				(width 0.1524)
				(type default)
			)
			(layer "F.SilkS")
		)
		(fp_line
			(start -0.7874 -0.4064)
			(end 0.7874 -0.4064)
			(stroke
				(width 0.1524)
				(type default)
			)
			(layer "F.SilkS")
		)
		(fp_line
			(start 0.67945 0.3048)
			(end 0.120396 0.3048)
			(stroke
				(width 0.1)
				(type default)
			)
			(layer "F.Fab")
		)
		(fp_line
			(start 0.67945 -0.3048)
			(end 0.67945 0.3048)
			(stroke
				(width 0.1)
				(type default)
			)
			(layer "F.Fab")
		)
		(fp_line
			(start 0.12065 -0.2794)
			(end 0.12065 -0.3048)
			(stroke
				(width 0.1)
				(type default)
			)
			(layer "F.Fab")
		)
		(fp_line
			(start 0.12065 -0.3048)
			(end 0.67945 -0.3048)
			(stroke
				(width 0.1)
				(type default)
			)
			(layer "F.Fab")
		)
		(fp_line
			(start 0.120396 0.3048)
			(end 0.120396 0.2794)
			(stroke
				(width 0.1)
				(type default)
			)
			(layer "F.Fab")
		)
		(fp_line
			(start 0.120396 0.2794)
			(end -0.12065 0.2794)
			(stroke
				(width 0.1)
				(type default)
			)
			(layer "F.Fab")
		)
		(fp_line
			(start -0.12065 0.3048)
			(end -0.67945 0.3048)
			(stroke
				(width 0.1)
				(type default)
			)
			(layer "F.Fab")
		)
		(fp_line
			(start -0.12065 0.2794)
			(end -0.12065 0.3048)
			(stroke
				(width 0.1)
				(type default)
			)
			(layer "F.Fab")
		)
		(fp_line
			(start -0.12065 -0.2794)
			(end 0.12065 -0.2794)
			(stroke
				(width 0.1)
				(type default)
			)
			(layer "F.Fab")
		)
		(fp_line
			(start -0.12065 -0.305054)
			(end -0.12065 -0.2794)
			(stroke
				(width 0.1)
				(type default)
			)
			(layer "F.Fab")
		)
		(fp_line
			(start -0.67945 0.3048)
			(end -0.67945 -0.305054)
			(stroke
				(width 0.1)
				(type default)
			)
			(layer "F.Fab")
		)
		(fp_line
			(start -0.67945 -0.305054)
			(end -0.12065 -0.305054)
			(stroke
				(width 0.1)
				(type default)
			)
			(layer "F.Fab")
		)
		(pad "1" smd circle
			(at -0.40005 0 180)
			(size 0 0)
			(layers "F.Cu" "F.Mask" "F.Paste")
			(net "HSC_SS")
		)
		(pad "2" smd circle
			(at 0.40005 0 180)
			(size 0 0)
			(layers "F.Cu" "F.Mask" "F.Paste")
			(net "AGND_HSC")
		)
	)
	(footprint ""
		(layer "F.Cu")
		(at 374.325642 -350.780858)
		(property "Reference" "PC1248"
			(at 0 0 0)
			(layer "F.SilkS")
			(hide yes)
			(effects
				(font
					(size 1.27 1.27)
				)
			)
		)
		(property "Value" ""
			(at 0 0 0)
			(layer "F.Fab")
			(effects
				(font
					(size 1.27 1.27)
				)
			)
		)
		(duplicate_pad_numbers_are_jumpers no)
		(fp_line
			(start -1.524 -0.762)
			(end 1.524 -0.762)
			(stroke
				(width 0.1524)
				(type default)
			)
			(layer "F.SilkS")
		)
		(fp_line
			(start -1.524 0.762)
			(end -1.524 -0.762)
			(stroke
				(width 0.1524)
				(type default)
			)
			(layer "F.SilkS")
		)
		(fp_line
			(start 1.524 -0.762)
			(end 1.524 0.762)
			(stroke
				(width 0.1524)
				(type default)
			)
			(layer "F.SilkS")
		)
		(fp_line
			(start 1.524 0.762)
			(end -1.524 0.762)
			(stroke
				(width 0.1524)
				(type default)
			)
			(layer "F.SilkS")
		)
		(fp_line
			(start -1.1049 -0.724916)
			(end -1.1049 0.724916)
			(stroke
				(width 0.1)
				(type default)
			)
			(layer "F.Fab")
		)
		(fp_line
			(start -1.1049 0.724916)
			(end 1.1049 0.724916)
			(stroke
				(width 0.1)
				(type default)
			)
			(layer "F.Fab")
		)
		(fp_line
			(start 1.1049 -0.724916)
			(end -1.1049 -0.724916)
			(stroke
				(width 0.1)
				(type default)
			)
			(layer "F.Fab")
		)
		(fp_line
			(start 1.1049 0.724916)
			(end 1.1049 -0.724916)
			(stroke
				(width 0.1)
				(type default)
			)
			(layer "F.Fab")
		)
		(pad "1" smd rect
			(at -0.889 0 180)
			(size 1.016 1.27)
			(layers "F.Cu" "F.Mask" "F.Paste")
			(net "SW_P12V_PVCCIN_CPU0_FLT")
		)
		(pad "2" smd rect
			(at 0.889 0 180)
			(size 1.016 1.27)
			(layers "F.Cu" "F.Mask" "F.Paste")
			(net "GND")
		)
	)
	(footprint ""
		(layer "F.Cu")
		(at 163.88715 -419.911276)
		(property "Reference" "R2724"
			(at 0 0 0)
			(layer "F.SilkS")
			(hide yes)
			(effects
				(font
					(size 1.27 1.27)
				)
			)
		)
		(property "Value" ""
			(at 0 0 0)
			(layer "F.Fab")
			(effects
				(font
					(size 1.27 1.27)
				)
			)
		)
		(duplicate_pad_numbers_are_jumpers no)
		(fp_line
			(start -0.7874 -0.4064)
			(end 0.7874 -0.4064)
			(stroke
				(width 0.1524)
				(type default)
			)
			(layer "F.SilkS")
		)
		(fp_line
			(start -0.7874 0.4064)
			(end -0.7874 -0.4064)
			(stroke
				(width 0.1524)
				(type default)
			)
			(layer "F.SilkS")
		)
		(fp_line
			(start 0.7874 -0.4064)
			(end 0.7874 0.4064)
			(stroke
				(width 0.1524)
				(type default)
			)
			(layer "F.SilkS")
		)
		(fp_line
			(start 0.7874 0.4064)
			(end -0.7874 0.4064)
			(stroke
				(width 0.1524)
				(type default)
			)
			(layer "F.SilkS")
		)
		(fp_line
			(start -0.67945 -0.305054)
			(end -0.12065 -0.305054)
			(stroke
				(width 0.1)
				(type default)
			)
			(layer "F.Fab")
		)
		(fp_line
			(start -0.67945 0.3048)
			(end -0.67945 -0.305054)
			(stroke
				(width 0.1)
				(type default)
			)
			(layer "F.Fab")
		)
		(fp_line
			(start -0.12065 -0.305054)
			(end -0.12065 -0.2794)
			(stroke
				(width 0.1)
				(type default)
			)
			(layer "F.Fab")
		)
		(fp_line
			(start -0.12065 -0.2794)
			(end 0.12065 -0.2794)
			(stroke
				(width 0.1)
				(type default)
			)
			(layer "F.Fab")
		)
		(fp_line
			(start -0.12065 0.2794)
			(end -0.12065 0.3048)
			(stroke
				(width 0.1)
				(type default)
			)
			(layer "F.Fab")
		)
		(fp_line
			(start -0.12065 0.3048)
			(end -0.67945 0.3048)
			(stroke
				(width 0.1)
				(type default)
			)
			(layer "F.Fab")
		)
		(fp_line
			(start 0.120396 0.2794)
			(end -0.12065 0.2794)
			(stroke
				(width 0.1)
				(type default)
			)
			(layer "F.Fab")
		)
		(fp_line
			(start 0.120396 0.3048)
			(end 0.120396 0.2794)
			(stroke
				(width 0.1)
				(type default)
			)
			(layer "F.Fab")
		)
		(fp_line
			(start 0.12065 -0.3048)
			(end 0.67945 -0.3048)
			(stroke
				(width 0.1)
				(type default)
			)
			(layer "F.Fab")
		)
		(fp_line
			(start 0.12065 -0.2794)
			(end 0.12065 -0.3048)
			(stroke
				(width 0.1)
				(type default)
			)
			(layer "F.Fab")
		)
		(fp_line
			(start 0.67945 -0.3048)
			(end 0.67945 0.3048)
			(stroke
				(width 0.1)
				(type default)
			)
			(layer "F.Fab")
		)
		(fp_line
			(start 0.67945 0.3048)
			(end 0.120396 0.3048)
			(stroke
				(width 0.1)
				(type default)
			)
			(layer "F.Fab")
		)
		(pad "1" smd circle
			(at -0.40005 0)
			(size 0 0)
			(layers "F.Cu" "F.Mask" "F.Paste")
			(net "SMB_BMC_SWB_R_SDA")
		)
		(pad "2" smd circle
			(at 0.40005 0)
			(size 0 0)
			(layers "F.Cu" "F.Mask" "F.Paste")
			(net "SMB_BMC_SWB_BUF_R_SDA")
		)
	)
	(footprint ""
		(layer "F.Cu")
		(at 402.94433 -402.371052 -90)
		(property "Reference" "C954"
			(at 0 0 270)
			(layer "F.SilkS")
			(hide yes)
			(effects
				(font
					(size 1.27 1.27)
				)
			)
		)
		(property "Value" ""
			(at 0 0 270)
			(layer "F.Fab")
			(effects
				(font
					(size 1.27 1.27)
				)
			)
		)
		(duplicate_pad_numbers_are_jumpers no)
		(fp_line
			(start -0.299974 0.150114)
			(end -0.299974 -0.150114)
			(stroke
				(width 0.1)
				(type default)
			)
			(layer "F.Fab")
		)
		(fp_line
			(start 0.299974 0.150114)
			(end -0.299974 0.150114)
			(stroke
				(width 0.1)
				(type default)
			)
			(layer "F.Fab")
		)
		(fp_line
			(start -0.299974 -0.150114)
			(end 0.299974 -0.150114)
			(stroke
				(width 0.1)
				(type default)
			)
			(layer "F.Fab")
		)
		(fp_line
			(start 0.299974 -0.150114)
			(end 0.299974 0.150114)
			(stroke
				(width 0.1)
				(type default)
			)
			(layer "F.Fab")
		)
		(pad "1" smd rect
			(at -0.2667 0 270)
			(size 0.3048 0.381)
			(layers "F.Cu" "F.Mask" "F.Paste")
			(net "P5E_CPU0_PE2_TX_C_DN<5>")
		)
		(pad "2" smd rect
			(at 0.2667 0 270)
			(size 0.3048 0.381)
			(layers "F.Cu" "F.Mask" "F.Paste")
			(net "P5E_CPU0_PE2_TX_DN<5>")
		)
	)
	(footprint ""
		(layer "F.Cu")
		(at 152.108154 -408.517344 -90)
		(property "Reference" "C1536"
			(at 0 0 270)
			(layer "F.SilkS")
			(hide yes)
			(effects
				(font
					(size 1.27 1.27)
				)
			)
		)
		(property "Value" ""
			(at 0 0 270)
			(layer "F.Fab")
			(effects
				(font
					(size 1.27 1.27)
				)
			)
		)
		(duplicate_pad_numbers_are_jumpers no)
		(fp_line
			(start -0.299974 0.150114)
			(end -0.299974 -0.150114)
			(stroke
				(width 0.1)
				(type default)
			)
			(layer "F.Fab")
		)
		(fp_line
			(start 0.299974 0.150114)
			(end -0.299974 0.150114)
			(stroke
				(width 0.1)
				(type default)
			)
			(layer "F.Fab")
		)
		(fp_line
			(start -0.299974 -0.150114)
			(end 0.299974 -0.150114)
			(stroke
				(width 0.1)
				(type default)
			)
			(layer "F.Fab")
		)
		(fp_line
			(start 0.299974 -0.150114)
			(end 0.299974 0.150114)
			(stroke
				(width 0.1)
				(type default)
			)
			(layer "F.Fab")
		)
		(pad "1" smd rect
			(at -0.2667 0 270)
			(size 0.3048 0.381)
			(layers "F.Cu" "F.Mask" "F.Paste")
			(net "P5E_CPU1_PE3_TX_C_DN<5>")
		)
		(pad "2" smd rect
			(at 0.2667 0 270)
			(size 0.3048 0.381)
			(layers "F.Cu" "F.Mask" "F.Paste")
			(net "P5E_CPU1_PE3_TX_DN<5>")
		)
	)
	(footprint ""
		(layer "F.Cu")
		(at 162.848036 -63.297308 180)
		(property "Reference" "R2125"
			(at 0 0 180)
			(layer "F.SilkS")
			(hide yes)
			(effects
				(font
					(size 1.27 1.27)
				)
			)
		)
		(property "Value" ""
			(at 0 0 180)
			(layer "F.Fab")
			(effects
				(font
					(size 1.27 1.27)
				)
			)
		)
		(duplicate_pad_numbers_are_jumpers no)
		(fp_line
			(start 0.7874 0.4064)
			(end -0.7874 0.4064)
			(stroke
				(width 0.1524)
				(type default)
			)
			(layer "F.SilkS")
		)
		(fp_line
			(start 0.7874 -0.4064)
			(end 0.7874 0.4064)
			(stroke
				(width 0.1524)
				(type default)
			)
			(layer "F.SilkS")
		)
		(fp_line
			(start -0.7874 0.4064)
			(end -0.7874 -0.4064)
			(stroke
				(width 0.1524)
				(type default)
			)
			(layer "F.SilkS")
		)
		(fp_line
			(start -0.7874 -0.4064)
			(end 0.7874 -0.4064)
			(stroke
				(width 0.1524)
				(type default)
			)
			(layer "F.SilkS")
		)
		(fp_line
			(start 0.67945 0.3048)
			(end 0.120396 0.3048)
			(stroke
				(width 0.1)
				(type default)
			)
			(layer "F.Fab")
		)
		(fp_line
			(start 0.67945 -0.3048)
			(end 0.67945 0.3048)
			(stroke
				(width 0.1)
				(type default)
			)
			(layer "F.Fab")
		)
		(fp_line
			(start 0.12065 -0.2794)
			(end 0.12065 -0.3048)
			(stroke
				(width 0.1)
				(type default)
			)
			(layer "F.Fab")
		)
		(fp_line
			(start 0.12065 -0.3048)
			(end 0.67945 -0.3048)
			(stroke
				(width 0.1)
				(type default)
			)
			(layer "F.Fab")
		)
		(fp_line
			(start 0.120396 0.3048)
			(end 0.120396 0.2794)
			(stroke
				(width 0.1)
				(type default)
			)
			(layer "F.Fab")
		)
		(fp_line
			(start 0.120396 0.2794)
			(end -0.12065 0.2794)
			(stroke
				(width 0.1)
				(type default)
			)
			(layer "F.Fab")
		)
		(fp_line
			(start -0.12065 0.3048)
			(end -0.67945 0.3048)
			(stroke
				(width 0.1)
				(type default)
			)
			(layer "F.Fab")
		)
		(fp_line
			(start -0.12065 0.2794)
			(end -0.12065 0.3048)
			(stroke
				(width 0.1)
				(type default)
			)
			(layer "F.Fab")
		)
		(fp_line
			(start -0.12065 -0.2794)
			(end 0.12065 -0.2794)
			(stroke
				(width 0.1)
				(type default)
			)
			(layer "F.Fab")
		)
		(fp_line
			(start -0.12065 -0.305054)
			(end -0.12065 -0.2794)
			(stroke
				(width 0.1)
				(type default)
			)
			(layer "F.Fab")
		)
		(fp_line
			(start -0.67945 0.3048)
			(end -0.67945 -0.305054)
			(stroke
				(width 0.1)
				(type default)
			)
			(layer "F.Fab")
		)
		(fp_line
			(start -0.67945 -0.305054)
			(end -0.12065 -0.305054)
			(stroke
				(width 0.1)
				(type default)
			)
			(layer "F.Fab")
		)
		(pad "1" smd circle
			(at -0.40005 0 180)
			(size 0 0)
			(layers "F.Cu" "F.Mask" "F.Paste")
			(net "P3V3_AUX")
		)
		(pad "2" smd circle
			(at 0.40005 0 180)
			(size 0 0)
			(layers "F.Cu" "F.Mask" "F.Paste")
			(net "SMB_PCIE_E1S_ISO_EN")
		)
	)
	(footprint ""
		(layer "F.Cu")
		(at 410.094176 -153.069036 180)
		(property "Reference" "PL3"
			(at -1.462786 -4.512564 0)
			(unlocked yes)
			(layer "F.SilkS")
			(effects
				(font
					(size 0.7874 0.5842)
					(thickness 0.1524)
				)
				(justify left)
			)
		)
		(property "Value" ""
			(at 0 0 180)
			(layer "F.Fab")
			(effects
				(font
					(size 1.27 1.27)
				)
			)
		)
		(duplicate_pad_numbers_are_jumpers no)
		(fp_line
			(start 4.800092 3.199892)
			(end -4.800092 3.199892)
			(stroke
				(width 0.1524)
				(type default)
			)
			(layer "F.SilkS")
		)
		(fp_line
			(start 4.800092 1.6891)
			(end 4.800092 3.199892)
			(stroke
				(width 0.1524)
				(type default)
			)
			(layer "F.SilkS")
		)
		(fp_line
			(start 4.800092 -3.199892)
			(end 4.800092 -1.6891)
			(stroke
				(width 0.1524)
				(type default)
			)
			(layer "F.SilkS")
		)
		(fp_line
			(start -4.800092 3.199892)
			(end -4.800092 1.6891)
			(stroke
				(width 0.1524)
				(type default)
			)
			(layer "F.SilkS")
		)
		(fp_line
			(start -4.800092 -1.6891)
			(end -4.800092 -3.199892)
			(stroke
				(width 0.1524)
				(type default)
			)
			(layer "F.SilkS")
		)
		(fp_line
			(start -4.800092 -3.199892)
			(end 4.800092 -3.199892)
			(stroke
				(width 0.1524)
				(type default)
			)
			(layer "F.SilkS")
		)
		(fp_line
			(start 4.800092 3.199892)
			(end -4.800092 3.199892)
			(stroke
				(width 0.1)
				(type default)
			)
			(layer "F.Fab")
		)
		(fp_line
			(start 4.800092 -3.199892)
			(end 4.800092 3.199892)
			(stroke
				(width 0.1)
				(type default)
			)
			(layer "F.Fab")
		)
		(fp_line
			(start -4.800092 3.199892)
			(end -4.800092 -3.199892)
			(stroke
				(width 0.1)
				(type default)
			)
			(layer "F.Fab")
		)
		(fp_line
			(start -4.800092 -3.199892)
			(end 4.800092 -3.199892)
			(stroke
				(width 0.1)
				(type default)
			)
			(layer "F.Fab")
		)
		(pad "1" smd rect
			(at -3.350006 0 270)
			(size 3.0988 3.2004)
			(layers "F.Cu" "F.Mask" "F.Paste")
			(net "SW_PVCCFA_EHV_CPU0_SW1")
		)
		(pad "2" smd rect
			(at 3.350006 0 270)
			(size 3.0988 3.2004)
			(layers "F.Cu" "F.Mask" "F.Paste")
			(net "PVCCFA_EHV_CPU0")
		)
	)
	(footprint ""
		(layer "F.Cu")
		(at 392.10488 -148.808948 90)
		(property "Reference" "R979"
			(at 0 0 90)
			(layer "F.SilkS")
			(hide yes)
			(effects
				(font
					(size 1.27 1.27)
				)
			)
		)
		(property "Value" ""
			(at 0 0 90)
			(layer "F.Fab")
			(effects
				(font
					(size 1.27 1.27)
				)
			)
		)
		(duplicate_pad_numbers_are_jumpers no)
		(fp_line
			(start 0.7874 -0.4064)
			(end 0.7874 0.4064)
			(stroke
				(width 0.1524)
				(type default)
			)
			(layer "F.SilkS")
		)
		(fp_line
			(start -0.7874 -0.4064)
			(end 0.7874 -0.4064)
			(stroke
				(width 0.1524)
				(type default)
			)
			(layer "F.SilkS")
		)
		(fp_line
			(start 0.7874 0.4064)
			(end -0.7874 0.4064)
			(stroke
				(width 0.1524)
				(type default)
			)
			(layer "F.SilkS")
		)
		(fp_line
			(start -0.7874 0.4064)
			(end -0.7874 -0.4064)
			(stroke
				(width 0.1524)
				(type default)
			)
			(layer "F.SilkS")
		)
		(fp_line
			(start -0.12065 -0.305054)
			(end -0.12065 -0.2794)
			(stroke
				(width 0.1)
				(type default)
			)
			(layer "F.Fab")
		)
		(fp_line
			(start -0.67945 -0.305054)
			(end -0.12065 -0.305054)
			(stroke
				(width 0.1)
				(type default)
			)
			(layer "F.Fab")
		)
		(fp_line
			(start 0.67945 -0.3048)
			(end 0.67945 0.3048)
			(stroke
				(width 0.1)
				(type default)
			)
			(layer "F.Fab")
		)
		(fp_line
			(start 0.12065 -0.3048)
			(end 0.67945 -0.3048)
			(stroke
				(width 0.1)
				(type default)
			)
			(layer "F.Fab")
		)
		(fp_line
			(start 0.12065 -0.2794)
			(end 0.12065 -0.3048)
			(stroke
				(width 0.1)
				(type default)
			)
			(layer "F.Fab")
		)
		(fp_line
			(start -0.12065 -0.2794)
			(end 0.12065 -0.2794)
			(stroke
				(width 0.1)
				(type default)
			)
			(layer "F.Fab")
		)
		(fp_line
			(start 0.120396 0.2794)
			(end -0.12065 0.2794)
			(stroke
				(width 0.1)
				(type default)
			)
			(layer "F.Fab")
		)
		(fp_line
			(start -0.12065 0.2794)
			(end -0.12065 0.3048)
			(stroke
				(width 0.1)
				(type default)
			)
			(layer "F.Fab")
		)
		(fp_line
			(start 0.67945 0.3048)
			(end 0.120396 0.3048)
			(stroke
				(width 0.1)
				(type default)
			)
			(layer "F.Fab")
		)
		(fp_line
			(start 0.120396 0.3048)
			(end 0.120396 0.2794)
			(stroke
				(width 0.1)
				(type default)
			)
			(layer "F.Fab")
		)
		(fp_line
			(start -0.12065 0.3048)
			(end -0.67945 0.3048)
			(stroke
				(width 0.1)
				(type default)
			)
			(layer "F.Fab")
		)
		(fp_line
			(start -0.67945 0.3048)
			(end -0.67945 -0.305054)
			(stroke
				(width 0.1)
				(type default)
			)
			(layer "F.Fab")
		)
		(pad "1" smd circle
			(at -0.40005 0 90)
			(size 0 0)
			(layers "F.Cu" "F.Mask" "F.Paste")
			(net "P3V3_AUX")
		)
		(pad "2" smd circle
			(at 0.40005 0 90)
			(size 0 0)
			(layers "F.Cu" "F.Mask" "F.Paste")
			(net "SMB_S3M_CPU0_3V3AUX_SDA")
		)
	)
)
